# BASEBOARD_FAB2 (Tioga Pass) — schematic netlist excerpt (pin names and nets, part order shuffled) for the footprints in the layout excerpt that follows; sources: Cadence DE-HDL packaged netlist, KiCad conversion of Wiwynn_Tioga_Pass_MB.brd

R3P53  RES  4.75K 1% CHIP  pkg 0402  page 133 : A = P1V05_PCH_STBY ; B = FM_OCP_MEZZC_PRES_1V05_PCH_N
C3L7  CAP  10UF 16V 10% X6S  pkg 0805  page 236 : A = VR_FET_SW_P12V_STBY_PVDDQ_DEF ; B = GND
C2P3  CAP_A  0.1UF 16V 10% X7R  pkg 0402V  page 192 : A = P3V3_STBY ; B = GND

(kicad_pcb
	(version 20260206)
	(generator "pcbnew")
	(generator_version "10.0")
	(general
		(thickness 1.6)
		(legacy_teardrops no)
	)
	(paper "A4")
	(title_block
		(title "Wiwynn_Tioga_Pass_MB.brd")
		(comment 1 "Tioga Pass / footprints 3016-3018 of 4770")
	)
	(layers
		(0 "F.Cu" signal "TOP")
		(4 "In1.Cu" signal "L2GND")
		(6 "In2.Cu" signal "L3")
		(8 "In3.Cu" signal "L4GND")
		(10 "In4.Cu" signal "L5")
		(12 "In5.Cu" signal "L6GND")
		(14 "In6.Cu" signal "L7VCC")
		(16 "In7.Cu" signal "L8VCC")
		(18 "In8.Cu" signal "L9GND")
		(20 "In9.Cu" signal "L10")
		(22 "In10.Cu" signal "L11GND")
		(24 "In11.Cu" signal "L12")
		(26 "In12.Cu" signal "L13GND")
		(2 "B.Cu" signal "BOTTOM")
		(9 "F.Adhes" user "F.Adhesive")
		(11 "B.Adhes" user "B.Adhesive")
		(13 "F.Paste" user "Package Geometry/Pastemask Top")
		(15 "B.Paste" user "Package Geometry/Pastemask Bottom")
		(5 "F.SilkS" user "Ref Des/Silkscreen Top")
		(7 "B.SilkS" user "Ref Des/Silkscreen Bottom")
		(1 "F.Mask" user "Board Geometry/Soldermask Top")
		(3 "B.Mask" user "Board Geometry/Soldermask Bottom")
		(17 "Dwgs.User" user "User.Drawings")
		(19 "Cmts.User" user "User.Comments")
		(21 "Eco1.User" user "User.Eco1")
		(23 "Eco2.User" user "User.Eco2")
		(25 "Edge.Cuts" user "Board Geometry/Outline")
		(27 "Margin" user)
		(31 "F.CrtYd" user "Package Geometry/Place Bound Top")
		(29 "B.CrtYd" user "Package Geometry/Place Bound Bottom")
		(35 "F.Fab" user "Ref Des/Assembly Top")
		(33 "B.Fab" user "Ref Des/Assembly Bottom")
	)
	(footprint ""
		(layer "B.Cu")
		(at 384.289808 -84.729828 180)
		(property "Reference" "R3P53"
			(at 0 0 0)
			(layer "B.SilkS")
			(hide yes)
			(effects
				(font
					(size 1.27 1.27)
				)
				(justify mirror)
			)
		)
		(property "Value" ""
			(at 0 0 0)
			(layer "B.Fab")
			(effects
				(font
					(size 1.27 1.27)
				)
				(justify mirror)
			)
		)
		(duplicate_pad_numbers_are_jumpers no)
		(fp_poly
			(pts
				(xy 0.2794 -0.1016) (xy -0.2794 -0.1016) (xy -0.2794 0.9906) (xy 0.2794 0.9906)
			)
			(stroke
				(width 0)
				(type default)
			)
			(fill no)
			(layer "B.CrtYd")
		)
		(fp_line
			(start 0.2794 0.9906)
			(end -0.2794 0.9906)
			(stroke
				(width 0.1)
				(type default)
			)
			(layer "B.Fab")
		)
		(fp_line
			(start 0.2794 -0.1016)
			(end 0.2794 0.9906)
			(stroke
				(width 0.1)
				(type default)
			)
			(layer "B.Fab")
		)
		(fp_line
			(start -0.2794 0.9906)
			(end -0.2794 -0.1016)
			(stroke
				(width 0.1)
				(type default)
			)
			(layer "B.Fab")
		)
		(fp_line
			(start -0.2794 -0.1016)
			(end 0.2794 -0.1016)
			(stroke
				(width 0.1)
				(type default)
			)
			(layer "B.Fab")
		)
		(pad "1" smd rect
			(at 0 0)
			(size 0.508 0.508)
			(layers "B.Cu" "B.Mask" "B.Paste")
			(net "P1V05_PCH_STBY")
		)
		(pad "2" smd rect
			(at 0 0.889)
			(size 0.508 0.508)
			(layers "B.Cu" "B.Mask" "B.Paste")
			(net "FM_OCP_MEZZC_PRES_1V05_PCH_N")
		)
		(zone
			(layer "B.Cu")
			(hatch none 0.5)
			(connect_pads
				(clearance 0)
			)
			(min_thickness 0.25)
			(keepout
				(tracks not_allowed)
				(vias allowed)
				(pads allowed)
				(copperpour not_allowed)
				(footprints allowed)
			)
			(placement
				(enabled no)
				(sheetname "")
			)
			(fill
				(thermal_gap 0.5)
				(thermal_bridge_width 0.5)
				(island_removal_mode 0)
			)
			(polygon
				(pts
					(xy 384.035808 -85.364828) (xy 384.543808 -85.364828) (xy 384.543808 -84.983828) (xy 384.035808 -84.983828)
				)
			)
		)
		(zone
			(layer "B.Cu")
			(hatch none 0.5)
			(connect_pads
				(clearance 0)
			)
			(min_thickness 0.25)
			(keepout
				(tracks allowed)
				(vias not_allowed)
				(pads allowed)
				(copperpour not_allowed)
				(footprints allowed)
			)
			(placement
				(enabled no)
				(sheetname "")
			)
			(fill
				(thermal_gap 0.5)
				(thermal_bridge_width 0.5)
				(island_removal_mode 0)
			)
			(polygon
				(pts
					(xy 384.035808 -84.983828) (xy 384.543808 -84.983828) (xy 384.543808 -85.364828) (xy 384.035808 -85.364828)
				)
			)
		)
	)
	(footprint ""
		(layer "B.Cu")
		(at 384.725672 -154.721306)
		(property "Reference" "C3L7"
			(at 0 0 0)
			(layer "B.SilkS")
			(hide yes)
			(effects
				(font
					(size 1.27 1.27)
				)
				(justify mirror)
			)
		)
		(property "Value" ""
			(at 0 0 0)
			(layer "B.Fab")
			(effects
				(font
					(size 1.27 1.27)
				)
				(justify mirror)
			)
		)
		(duplicate_pad_numbers_are_jumpers no)
		(fp_poly
			(pts
				(xy 0.7239 -0.2159) (xy -0.7239 -0.2159) (xy -0.7239 1.9939) (xy 0.7239 1.9939)
			)
			(stroke
				(width 0)
				(type default)
			)
			(fill no)
			(layer "B.CrtYd")
		)
		(fp_line
			(start -0.7239 -0.2159)
			(end 0.7239 -0.2159)
			(stroke
				(width 0.1)
				(type default)
			)
			(layer "B.Fab")
		)
		(fp_line
			(start -0.7239 1.9939)
			(end -0.7239 -0.2159)
			(stroke
				(width 0.1)
				(type default)
			)
			(layer "B.Fab")
		)
		(fp_line
			(start 0.7239 -0.2159)
			(end 0.7239 1.9939)
			(stroke
				(width 0.1)
				(type default)
			)
			(layer "B.Fab")
		)
		(fp_line
			(start 0.7239 1.9939)
			(end -0.7239 1.9939)
			(stroke
				(width 0.1)
				(type default)
			)
			(layer "B.Fab")
		)
		(pad "1" smd rect
			(at 0 0 180)
			(size 1.27 1.016)
			(layers "B.Cu" "B.Mask" "B.Paste")
			(net "VR_FET_SW_P12V_STBY_PVDDQ_DEF")
		)
		(pad "2" smd rect
			(at 0 1.778 180)
			(size 1.27 1.016)
			(layers "B.Cu" "B.Mask" "B.Paste")
			(net "GND")
		)
		(zone
			(layer "B.Cu")
			(hatch none 0.5)
			(connect_pads
				(clearance 0)
			)
			(min_thickness 0.25)
			(keepout
				(tracks not_allowed)
				(vias allowed)
				(pads allowed)
				(copperpour not_allowed)
				(footprints allowed)
			)
			(placement
				(enabled no)
				(sheetname "")
			)
			(fill
				(thermal_gap 0.5)
				(thermal_bridge_width 0.5)
				(island_removal_mode 0)
			)
			(polygon
				(pts
					(xy 385.360672 -154.213306) (xy 384.090672 -154.213306) (xy 384.090672 -153.451306) (xy 385.360672 -153.451306)
				)
			)
		)
	)
	(footprint ""
		(layer "B.Cu")
		(at 379.74905 -68.707 -90)
		(property "Reference" "C2P3"
			(at 0 0 90)
			(layer "B.SilkS")
			(hide yes)
			(effects
				(font
					(size 1.27 1.27)
				)
				(justify mirror)
			)
		)
		(property "Value" ""
			(at 0 0 90)
			(layer "B.Fab")
			(effects
				(font
					(size 1.27 1.27)
				)
				(justify mirror)
			)
		)
		(duplicate_pad_numbers_are_jumpers no)
		(fp_rect
			(start 0.2794 0.9144)
			(end -0.2794 -0.1143)
			(stroke
				(width 0)
				(type default)
			)
			(fill no)
			(layer "B.CrtYd")
		)
		(fp_line
			(start -0.2794 0.9144)
			(end 0.2794 0.9144)
			(stroke
				(width 0.1)
				(type default)
			)
			(layer "B.Fab")
		)
		(fp_line
			(start 0.2794 0.9144)
			(end 0.2794 -0.1143)
			(stroke
				(width 0.1)
				(type default)
			)
			(layer "B.Fab")
		)
		(fp_line
			(start -0.2794 -0.1143)
			(end -0.2794 0.9144)
			(stroke
				(width 0.1)
				(type default)
			)
			(layer "B.Fab")
		)
		(fp_line
			(start 0.2794 -0.1143)
			(end -0.2794 -0.1143)
			(stroke
				(width 0.1)
				(type default)
			)
			(layer "B.Fab")
		)
		(pad "1" smd custom
			(at 0 0 180)
			(size 0.10414 0.10414)
			(layers "B.Cu" "B.Mask" "B.Paste")
			(net "P3V3_STBY")
			(options
				(clearance outline)
				(anchor circle)
			)
			(primitives
				(gr_poly
					(pts
						(xy -0.20828 -0.08636) (xy -0.20828 0.08636) (xy -0.08636 0.20828) (xy 0.086614 0.20828) (xy 0.20828 0.086614)
						(xy 0.20828 -0.08636) (xy 0.08636 -0.20828) (xy -0.08636 -0.20828)
					)
					(width 0)
					(fill yes)
				)
			)
		)
		(pad "2" smd custom
			(at 0 0.8001 180)
			(size 0.10414 0.10414)
			(layers "B.Cu" "B.Mask" "B.Paste")
			(net "GND")
			(options
				(clearance outline)
				(anchor circle)
			)
			(primitives
				(gr_poly
					(pts
						(xy -0.20828 -0.08636) (xy -0.20828 0.08636) (xy -0.08636 0.20828) (xy 0.086614 0.20828) (xy 0.20828 0.086614)
						(xy 0.20828 -0.08636) (xy 0.08636 -0.20828) (xy -0.08636 -0.20828)
					)
					(width 0)
					(fill yes)
				)
			)
		)
		(zone
			(layer "B.Cu")
			(hatch none 0.5)
			(connect_pads
				(clearance 0)
			)
			(min_thickness 0.25)
			(keepout
				(tracks not_allowed)
				(vias allowed)
				(pads allowed)
				(copperpour not_allowed)
				(footprints allowed)
			)
			(placement
				(enabled no)
				(sheetname "")
			)
			(fill
				(thermal_gap 0.5)
				(thermal_bridge_width 0.5)
				(island_removal_mode 0)
			)
			(polygon
				(pts
					(xy 379.5395 -68.61937) (xy 379.1585 -68.61937) (xy 379.1585 -68.79463) (xy 379.5395 -68.794884)
				)
			)
		)
		(zone
			(layer "B.Cu")
			(hatch none 0.5)
			(connect_pads
				(clearance 0)
			)
			(min_thickness 0.25)
			(keepout
				(tracks allowed)
				(vias not_allowed)
				(pads allowed)
				(copperpour not_allowed)
				(footprints allowed)
			)
			(placement
				(enabled no)
				(sheetname "")
			)
			(fill
				(thermal_gap 0.5)
				(thermal_bridge_width 0.5)
				(island_removal_mode 0)
			)
			(polygon
				(pts
					(xy 379.5395 -68.61937) (xy 379.1585 -68.61937) (xy 379.1585 -68.79463) (xy 379.5395 -68.794884)
				)
			)
		)
	)
)
